#ISCELL
  logical_power design_note *
  *
#ISCELL
  mstr_misc dns *
  *
#ISCELL
  pure_quanta quanta_title_block_c *
  *
#ISCELL
  logical_power universal_power *
  page15_i1
#ISCELL
  standard offpage *
  page15_i101
#ISCELL
  standard offpage *
  page15_i102
#ISCELL
  standard offpage *
  page15_i103
#CELL
  pure_quanta q_cap *
  page15_i117
#ISCELL
  logical_power universal_gnd *
  page15_i118
#CELL
  pure_quanta q_cap *
  page15_i119
#ISCELL
  standard offpage *
  page15_i120
#ISCELL
  standard offpage *
  page15_i125
#ISCELL
  standard offpage *
  page15_i126
#CELL
  pure_quanta q_res *
  page15_i128
#ISCELL
  standard offpage *
  page15_i130
#ISCELL
  standard offpage *
  page15_i131
#ISCELL
  standard offpage *
  page15_i132
#CELL
  pure_quanta q_res *
  page15_i133
#CELL
  pure_quanta q_res *
  page15_i134
#ISCELL
  standard offpage *
  page15_i135
#ISCELL
  standard offpage *
  page15_i136
#ISCELL
  standard offpage *
  page15_i137
#ISCELL
  standard offpage *
  page15_i138
#ISCELL
  standard offpage *
  page15_i139
#CELL
  pure_quanta q_cap *
  page15_i14
#CELL
  pure_quanta q_res *
  page15_i140
#CELL
  pure_quanta q_res *
  page15_i141
#CELL
  pure_quanta q_res *
  page15_i142
#ISCELL
  standard offpage *
  page15_i143
#ISCELL
  standard offpage *
  page15_i144
#ISCELL
  standard offpage *
  page15_i145
#ISCELL
  standard offpage *
  page15_i146
#ISCELL
  standard offpage *
  page15_i147
#ISCELL
  logical_power universal_gnd *
  page15_i148
#CELL
  pure_quanta q_res *
  page15_i149
#ISCELL
  logical_power universal_gnd *
  page15_i15
#CELL
  pure_quanta q_res *
  page15_i150
#CELL
  pure_quanta q_res *
  page15_i151
#CELL
  pure_quanta q_res *
  page15_i152
#ISCELL
  logical_power universal_power *
  page15_i154
#ISCELL
  standard offpage *
  page15_i155
#ISCELL
  standard offpage *
  page15_i159
#CELL
  pure_quanta q_cap *
  page15_i16
#CELL
  pure_quanta q_res *
  page15_i168
#CELL
  pure_quanta q_res *
  page15_i169
#ISCELL
  logical_power universal_gnd *
  page15_i17
#ISCELL
  standard offpage *
  page15_i170
#ISCELL
  standard offpage *
  page15_i171
#CELL
  pure_quanta q_res *
  page15_i174
#ISCELL
  logical_power vccaux15 *
  page15_i175
#ISCELL
  standard offpage *
  page15_i176
#CELL
  pure_quanta mosfet_n_gsd *
  page15_i179
#ISCELL
  logical_power universal_power *
  page15_i18
#CELL
  pure_quanta q_cap *
  page15_i180
#CELL
  pure_quanta q_res *
  page15_i181
#CELL
  pure_quanta q_res *
  page15_i183
#CELL
  pure_quanta q_res *
  page15_i184
#ISCELL
  standard offpage *
  page15_i185
#ISCELL
  standard offpage *
  page15_i186
#ISCELL
  logical_power universal_gnd *
  page15_i188
#ISCELL
  logical_power universal_gnd *
  page15_i189
#CELL
  pure_quanta q_res *
  page15_i19
#ISCELL
  standard offpage *
  page15_i190
#ISCELL
  standard offpage *
  page15_i191
#ISCELL
  logical_power universal_power *
  page15_i194
#ISCELL
  logical_power vccaux15 *
  page15_i195
#ISCELL
  logical_power vccaux15 *
  page15_i196
#ISCELL
  logical_power vccaux15 *
  page15_i197
#ISCELL
  logical_power vccaux15 *
  page15_i199
#CELL
  pure_quanta q_res *
  page15_i2
#ISCELL
  logical_power vccaux15 *
  page15_i200
#CELL
  pure_quanta q_cap *
  page15_i201
#CELL
  pure_quanta q_res *
  page15_i202
#CELL
  pure_quanta q_res *
  page15_i203
#ISCELL
  logical_power universal_gnd *
  page15_i204
#ISCELL
  standard offpage *
  page15_i205
#ISCELL
  standard offpage *
  page15_i206
#CELL
  pure_quanta q_cap *
  page15_i207
#CELL
  pure_quanta q_res *
  page15_i21
#ISCELL
  standard offpage *
  page15_i210
#CELL
  pure_quanta q_res *
  page15_i211
#ISCELL
  logical_power universal_gnd *
  page15_i212
#ISCELL
  standard offpage *
  page15_i213
#CELL
  pure_quanta q_cap *
  page15_i215
#ISCELL
  logical_power universal_gnd *
  page15_i216
#ISCELL
  standard offpage *
  page15_i217
#CELL
  pure_quanta q_res *
  page15_i219
#ISCELL
  logical_power universal_power *
  page15_i22
#CELL
  pure_quanta q_res *
  page15_i220
#ISCELL
  logical_power universal_power *
  page15_i221
#ISCELL
  standard offpage *
  page15_i222
#CELL
  pure_quanta q_res *
  page15_i223
#ISCELL
  standard offpage *
  page15_i228
#ISCELL
  standard offpage *
  page15_i229
#ISCELL
  logical_power universal_gnd *
  page15_i23
#ISCELL
  standard offpage *
  page15_i234
#CELL
  pure_quanta q_cap *
  page15_i235
#CELL
  pure_quanta q_res *
  page15_i236
#ISCELL
  logical_power universal_gnd *
  page15_i237
#ISCELL
  standard offpage *
  page15_i238
#CELL
  pure_quanta q_cap *
  page15_i24
#CELL
  pure_quanta q_cap *
  page15_i240
#CELL
  pure_quanta q_res *
  page15_i242
#ISCELL
  logical_power universal_gnd *
  page15_i243
#CELL
  pure_quanta q_res *
  page15_i244
#CELL
  pure_quanta q_res *
  page15_i245
#ISCELL
  standard offpage *
  page15_i246
#CELL
  pure_quanta q_cap *
  page15_i247
#ISCELL
  logical_power universal_power *
  page15_i25
#ISCELL
  logical_power universal_gnd *
  page15_i251
#CELL
  pure_quanta q_res *
  page15_i252
#ISCELL
  standard offpage *
  page15_i254
#CELL
  pure_quanta q_res *
  page15_i255
#CELL
  pure_quanta q_cap *
  page15_i256
#ISCELL
  logical_power universal_gnd *
  page15_i257
#ISCELL
  standard offpage *
  page15_i258
#CELL
  pure_quanta q_cap *
  page15_i259
#ISCELL
  standard offpage *
  page15_i26
#CELL
  pure_quanta q_res *
  page15_i261
#CELL
  pure_quanta q_res *
  page15_i262
#ISCELL
  logical_power universal_gnd *
  page15_i263
#ISCELL
  logical_power universal_power *
  page15_i264
#ISCELL
  standard offpage *
  page15_i265
#ISCELL
  standard offpage *
  page15_i266
#ISCELL
  standard offpage *
  page15_i267
#ISCELL
  standard offpage *
  page15_i27
#ISCELL
  standard offpage *
  page15_i270
#ISCELL
  standard offpage *
  page15_i271
#ISCELL
  standard offpage *
  page15_i272
#ISCELL
  standard offpage *
  page15_i275
#ISCELL
  standard offpage *
  page15_i28
#ISCELL
  standard offpage *
  page15_i287
#CELL
  pure_quanta q_res *
  page15_i289
#ISCELL
  standard offpage *
  page15_i29
#ISCELL
  standard offpage *
  page15_i292
#ISCELL
  standard offpage *
  page15_i293
#ISCELL
  standard offpage *
  page15_i294
#ISCELL
  standard offpage *
  page15_i299
#ISCELL
  logical_power universal_power *
  page15_i3
#ISCELL
  standard offpage *
  page15_i300
#ISCELL
  standard offpage *
  page15_i301
#ISCELL
  standard offpage *
  page15_i302
#ISCELL
  standard offpage *
  page15_i303
#ISCELL
  standard offpage *
  page15_i306
#ISCELL
  standard offpage *
  page15_i309
#ISCELL
  logical_power universal_power *
  page15_i31
#ISCELL
  standard offpage *
  page15_i311
#ISCELL
  standard offpage *
  page15_i312
#ISCELL
  standard offpage *
  page15_i313
#ISCELL
  standard offpage *
  page15_i315
#ISCELL
  standard offpage *
  page15_i316
#ISCELL
  standard offpage *
  page15_i317
#CELL
  pure_quanta q_res *
  page15_i318
#ISCELL
  standard offpage *
  page15_i319
#CELL
  pure_quanta q_res *
  page15_i32
#CELL
  pure_quanta q_res *
  page15_i320
#CELL
  pure_quanta q_res *
  page15_i321
#ISCELL
  standard offpage *
  page15_i322
#ISCELL
  standard offpage *
  page15_i323
#CELL
  pure_quanta q_res *
  page15_i326
#ISCELL
  standard offpage *
  page15_i327
#ISCELL
  logical_power universal_power *
  page15_i33
#CELL
  pure_quanta q_res *
  page15_i330
#ISCELL
  standard offpage *
  page15_i331
#CELL
  pure_quanta q_res *
  page15_i34
#ISCELL
  standard offpage *
  page15_i344
#CELL
  pure_quanta q_res *
  page15_i345
#CELL
  pure_quanta q_res *
  page15_i346
#ISCELL
  standard offpage *
  page15_i347
#ISCELL
  logical_power universal_gnd *
  page15_i35
#CELL
  pure_quanta ast2600a3gp *
  page15_i350
#CELL
  pure_quanta q_res *
  page15_i351
#ISCELL
  standard offpage *
  page15_i352
#CELL
  pure_quanta q_res *
  page15_i353
#CELL
  pure_quanta q_res *
  page15_i354
#ISCELL
  logical_power universal_gnd *
  page15_i355
#ISCELL
  standard offpage *
  page15_i357
#CELL
  pure_quanta q_cap *
  page15_i36
#ISCELL
  standard offpage *
  page15_i366
#CELL
  pure_quanta q_res *
  page15_i367
#CELL
  pure_quanta q_cap *
  page15_i368
#CELL
  pure_quanta q_cap *
  page15_i369
#CELL
  pure_quanta q_cap *
  page15_i37
#ISCELL
  standard offpage *
  page15_i370
#ISCELL
  standard offpage *
  page15_i371
#ISCELL
  standard offpage *
  page15_i372
#ISCELL
  standard offpage *
  page15_i373
#ISCELL
  standard offpage *
  page15_i378
#ISCELL
  standard offpage *
  page15_i379
#ISCELL
  logical_power universal_power *
  page15_i38
#ISCELL
  standard offpage *
  page15_i383
#ISCELL
  standard offpage *
  page15_i385
#ISCELL
  standard offpage *
  page15_i386
#CELL
  pure_quanta q_res *
  page15_i387
#CELL
  pure_quanta q_res *
  page15_i389
#CELL
  pure_quanta osc4_7x25000018 *
  page15_i39
#ISCELL
  standard offpage *
  page15_i390
#CELL
  pure_quanta q_res *
  page15_i391
#ISCELL
  standard offpage *
  page15_i392
#CELL
  pure_quanta 74lvc1g08gw *
  page15_i393
#ISCELL
  standard offpage *
  page15_i395
#ISCELL
  logical_power universal_gnd *
  page15_i396
#ISCELL
  logical_power vccaux15 *
  page15_i397
#CELL
  pure_quanta q_cap *
  page15_i398
#ISCELL
  logical_power universal_gnd *
  page15_i399
#CELL
  pure_quanta q_res *
  page15_i4
#ISCELL
  logical_power universal_gnd *
  page15_i40
#ISCELL
  standard offpage *
  page15_i400
#ISCELL
  standard offpage *
  page15_i401
#CELL
  pure_quanta q_res *
  page15_i404
#CELL
  pure_quanta q_res *
  page15_i405
#CELL
  pure_quanta q_res *
  page15_i406
#CELL
  pure_quanta q_res *
  page15_i42
#ISCELL
  logical_power universal_gnd *
  page15_i46
#CELL
  pure_quanta q_res *
  page15_i47
#ISCELL
  standard offpage *
  page15_i48
#ISCELL
  standard offpage *
  page15_i49
#ISCELL
  standard offpage *
  page15_i5
#ISCELL
  standard offpage *
  page15_i50
#CELL
  pure_quanta q_res *
  page15_i51
#ISCELL
  logical_power universal_power *
  page15_i52
#ISCELL
  standard offpage *
  page15_i53
#ISCELL
  standard offpage *
  page15_i61
#ISCELL
  logical_power universal_power *
  page15_i64
#CELL
  pure_quanta q_inductor *
  page15_i65
#ISCELL
  logical_power universal_gnd *
  page15_i66
#CELL
  pure_quanta q_cap *
  page15_i68
#ISCELL
  standard offpage *
  page15_i80
#ISCELL
  logical_power universal_power *
  page15_i81
#CELL
  pure_quanta q_inductor *
  page15_i82
#ISCELL
  standard offpage *
  page15_i83
#ISCELL
  standard offpage *
  page15_i84
#ISCELL
  standard offpage *
  page15_i85
#ISCELL
  standard offpage *
  page15_i86
#ISCELL
  logical_power universal_gnd *
  page15_i87
#CELL
  pure_quanta q_cap *
  page15_i89
#ISCELL
  standard offpage *
  page15_i90
#CELL
  pure_quanta q_res *
  page15_i92
#CELL
  pure_quanta q_res *
  page15_i93
#ISCELL
  standard offpage *
  page15_i94
#ISCELL
  standard offpage *
  page15_i95
#ISCELL
  standard offpage *
  page15_i96
